# SCM (Grand Teton) — schematic netlist excerpt (pin names and nets, part order shuffled) for the footprints in the layout excerpt that follows; sources: Cadence DE-HDL packaged netlist, KiCad conversion of 12092022_DA0F0TMDCD0_F0T_Management_Board_D_brd_V3_OCP.brd

C117  Q_CAP  1UF 25V 10% X6S  pkg C0402  page 16 : A = P1V2_AUX ; B = GND
R427  Q_RES  33.2 1% CHIP  pkg 0402LF  page 13 : A = UART_BMC_1_RXD_R ; B = UART_BMC_1_RXD

(kicad_pcb
	(version 20260206)
	(generator "pcbnew")
	(generator_version "10.0")
	(general
		(thickness 1.6)
		(legacy_teardrops no)
	)
	(paper "A4")
	(title_block
		(title "12092022_DA0F0TMDCD0_F0T_Management_Board_D_brd_V3_OCP.brd")
		(comment 1 "Grand Teton / footprints 972-973 of 1440")
	)
	(layers
		(0 "F.Cu" signal "TOP")
		(4 "In1.Cu" signal "GND")
		(6 "In2.Cu" signal "IN1")
		(8 "In3.Cu" signal "GND1")
		(10 "In4.Cu" signal "IN2")
		(12 "In5.Cu" signal "VCC")
		(14 "In6.Cu" signal "VCC1")
		(16 "In7.Cu" signal "IN3")
		(18 "In8.Cu" signal "GND2")
		(20 "In9.Cu" signal "IN4")
		(22 "In10.Cu" signal "GND3")
		(2 "B.Cu" signal "BOTTOM")
		(9 "F.Adhes" user "F.Adhesive")
		(11 "B.Adhes" user "B.Adhesive")
		(13 "F.Paste" user "Package Geometry/Pastemask Top")
		(15 "B.Paste" user "Package Geometry/Pastemask Bottom")
		(5 "F.SilkS" user "Ref Des/Silkscreen Top")
		(7 "B.SilkS" user "Ref Des/Silkscreen Bottom")
		(1 "F.Mask" user "Board Geometry/Soldermask Top")
		(3 "B.Mask" user "Board Geometry/Soldermask Bottom")
		(17 "Dwgs.User" user "User.Drawings")
		(19 "Cmts.User" user "User.Comments")
		(21 "Eco1.User" user "User.Eco1")
		(23 "Eco2.User" user "User.Eco2")
		(25 "Edge.Cuts" user "Board Geometry/Outline")
		(27 "Margin" user)
		(31 "F.CrtYd" user "Package Geometry/Place Bound Top")
		(29 "B.CrtYd" user "Package Geometry/Place Bound Bottom")
		(35 "F.Fab" user "Ref Des/Assembly Top")
		(33 "B.Fab" user "Ref Des/Assembly Bottom")
	)
	(footprint ""
		(layer "B.Cu")
		(at 60.85586 -30.867604 -90)
		(property "Reference" "R427"
			(at 0 0 90)
			(layer "B.SilkS")
			(hide yes)
			(effects
				(font
					(size 1.27 1.27)
				)
				(justify mirror)
			)
		)
		(property "Value" ""
			(at 0 0 90)
			(layer "B.Fab")
			(effects
				(font
					(size 1.27 1.27)
				)
				(justify mirror)
			)
		)
		(duplicate_pad_numbers_are_jumpers no)
		(fp_line
			(start -0.7874 0.4064)
			(end 0.7874 0.4064)
			(stroke
				(width 0.1524)
				(type default)
			)
			(layer "B.SilkS")
		)
		(fp_line
			(start 0.7874 0.4064)
			(end 0.7874 -0.4064)
			(stroke
				(width 0.1524)
				(type default)
			)
			(layer "B.SilkS")
		)
		(fp_line
			(start -0.7874 -0.4064)
			(end -0.7874 0.4064)
			(stroke
				(width 0.1524)
				(type default)
			)
			(layer "B.SilkS")
		)
		(fp_line
			(start 0.7874 -0.4064)
			(end -0.7874 -0.4064)
			(stroke
				(width 0.1524)
				(type default)
			)
			(layer "B.SilkS")
		)
		(fp_line
			(start -0.67945 0.3048)
			(end -0.120396 0.3048)
			(stroke
				(width 0.1)
				(type default)
			)
			(layer "B.Fab")
		)
		(fp_line
			(start -0.120396 0.3048)
			(end -0.120396 0.2794)
			(stroke
				(width 0.1)
				(type default)
			)
			(layer "B.Fab")
		)
		(fp_line
			(start 0.12065 0.3048)
			(end 0.67945 0.3048)
			(stroke
				(width 0.1)
				(type default)
			)
			(layer "B.Fab")
		)
		(fp_line
			(start 0.67945 0.3048)
			(end 0.67945 -0.305054)
			(stroke
				(width 0.1)
				(type default)
			)
			(layer "B.Fab")
		)
		(fp_line
			(start -0.120396 0.2794)
			(end 0.12065 0.2794)
			(stroke
				(width 0.1)
				(type default)
			)
			(layer "B.Fab")
		)
		(fp_line
			(start 0.12065 0.2794)
			(end 0.12065 0.3048)
			(stroke
				(width 0.1)
				(type default)
			)
			(layer "B.Fab")
		)
		(fp_line
			(start -0.12065 -0.2794)
			(end -0.12065 -0.3048)
			(stroke
				(width 0.1)
				(type default)
			)
			(layer "B.Fab")
		)
		(fp_line
			(start 0.12065 -0.2794)
			(end -0.12065 -0.2794)
			(stroke
				(width 0.1)
				(type default)
			)
			(layer "B.Fab")
		)
		(fp_line
			(start -0.67945 -0.3048)
			(end -0.67945 0.3048)
			(stroke
				(width 0.1)
				(type default)
			)
			(layer "B.Fab")
		)
		(fp_line
			(start -0.12065 -0.3048)
			(end -0.67945 -0.3048)
			(stroke
				(width 0.1)
				(type default)
			)
			(layer "B.Fab")
		)
		(fp_line
			(start 0.12065 -0.305054)
			(end 0.12065 -0.2794)
			(stroke
				(width 0.1)
				(type default)
			)
			(layer "B.Fab")
		)
		(fp_line
			(start 0.67945 -0.305054)
			(end 0.12065 -0.305054)
			(stroke
				(width 0.1)
				(type default)
			)
			(layer "B.Fab")
		)
		(pad "1" smd circle
			(at 0.40005 0 90)
			(size 0 0)
			(layers "B.Cu" "B.Mask" "B.Paste")
			(net "UART_BMC_1_RXD_R")
		)
		(pad "2" smd circle
			(at -0.40005 0 90)
			(size 0 0)
			(layers "B.Cu" "B.Mask" "B.Paste")
			(net "UART_BMC_1_RXD")
		)
	)
	(footprint ""
		(layer "B.Cu")
		(at 53.006498 -49.3903)
		(property "Reference" "C117"
			(at 0 0 0)
			(layer "B.SilkS")
			(hide yes)
			(effects
				(font
					(size 1.27 1.27)
				)
				(justify mirror)
			)
		)
		(property "Value" ""
			(at 0 0 0)
			(layer "B.Fab")
			(effects
				(font
					(size 1.27 1.27)
				)
				(justify mirror)
			)
		)
		(duplicate_pad_numbers_are_jumpers no)
		(fp_line
			(start -0.7874 -0.4064)
			(end -0.7874 0.4064)
			(stroke
				(width 0.1524)
				(type default)
			)
			(layer "B.SilkS")
		)
		(fp_line
			(start -0.7874 0.4064)
			(end 0.7874 0.4064)
			(stroke
				(width 0.1524)
				(type default)
			)
			(layer "B.SilkS")
		)
		(fp_line
			(start 0.7874 -0.4064)
			(end -0.7874 -0.4064)
			(stroke
				(width 0.1524)
				(type default)
			)
			(layer "B.SilkS")
		)
		(fp_line
			(start 0.7874 0.4064)
			(end 0.7874 -0.4064)
			(stroke
				(width 0.1524)
				(type default)
			)
			(layer "B.SilkS")
		)
		(fp_line
			(start -0.67945 -0.3048)
			(end -0.67945 0.3048)
			(stroke
				(width 0.1)
				(type default)
			)
			(layer "B.Fab")
		)
		(fp_line
			(start -0.67945 0.3048)
			(end -0.120396 0.3048)
			(stroke
				(width 0.1)
				(type default)
			)
			(layer "B.Fab")
		)
		(fp_line
			(start -0.12065 -0.3048)
			(end -0.67945 -0.3048)
			(stroke
				(width 0.1)
				(type default)
			)
			(layer "B.Fab")
		)
		(fp_line
			(start -0.12065 -0.2794)
			(end -0.12065 -0.3048)
			(stroke
				(width 0.1)
				(type default)
			)
			(layer "B.Fab")
		)
		(fp_line
			(start -0.120396 0.2794)
			(end 0.12065 0.2794)
			(stroke
				(width 0.1)
				(type default)
			)
			(layer "B.Fab")
		)
		(fp_line
			(start -0.120396 0.3048)
			(end -0.120396 0.2794)
			(stroke
				(width 0.1)
				(type default)
			)
			(layer "B.Fab")
		)
		(fp_line
			(start 0.12065 -0.305054)
			(end 0.12065 -0.2794)
			(stroke
				(width 0.1)
				(type default)
			)
			(layer "B.Fab")
		)
		(fp_line
			(start 0.12065 -0.2794)
			(end -0.12065 -0.2794)
			(stroke
				(width 0.1)
				(type default)
			)
			(layer "B.Fab")
		)
		(fp_line
			(start 0.12065 0.2794)
			(end 0.12065 0.3048)
			(stroke
				(width 0.1)
				(type default)
			)
			(layer "B.Fab")
		)
		(fp_line
			(start 0.12065 0.3048)
			(end 0.67945 0.3048)
			(stroke
				(width 0.1)
				(type default)
			)
			(layer "B.Fab")
		)
		(fp_line
			(start 0.67945 -0.305054)
			(end 0.12065 -0.305054)
			(stroke
				(width 0.1)
				(type default)
			)
			(layer "B.Fab")
		)
		(fp_line
			(start 0.67945 0.3048)
			(end 0.67945 -0.305054)
			(stroke
				(width 0.1)
				(type default)
			)
			(layer "B.Fab")
		)
		(pad "1" smd circle
			(at 0.40005 0 180)
			(size 0 0)
			(layers "B.Cu" "B.Mask" "B.Paste")
			(net "P1V2_AUX")
		)
		(pad "2" smd circle
			(at -0.40005 0 180)
			(size 0 0)
			(layers "B.Cu" "B.Mask" "B.Paste")
			(net "GND")
		)
	)
)
